# S9S_MB_2U (Grand Teton) — schematic netlist excerpt (pin names and nets, part order shuffled) for the footprints in the layout excerpt that follows; sources: Cadence DE-HDL packaged netlist, KiCad conversion of 03242023_DA0F0TMBIJ0_F0T_Motherboard_J_brd_V01_OCP.brd

PC726_P1_3  Q_CAP  22UF 16V 20% X6S  pkg C0805  page 290 : A = SW_P12V_PVCCFA_EHV_FIVRA_CPU1_R ; B = GND
PR345  Q_RES  0 5% CHIP  pkg 0402LF  page 266 : A = SH_PVCCFA_EHV_FIVRA_CPU0 ; B = SH_PVCCFA_EHV_FIVRA_CPU0_R
PC2215  Q_CAP  3900PF 50V 10% EMPTY  pkg C0402  page 192 : A = P12V_E1S_GATE_0 ; B = GND

(kicad_pcb
	(version 20260206)
	(generator "pcbnew")
	(generator_version "10.0")
	(general
		(thickness 1.6)
		(legacy_teardrops no)
	)
	(paper "A4")
	(title_block
		(title "03242023_DA0F0TMBIJ0_F0T_Motherboard_J_brd_V01_OCP.brd")
		(comment 1 "Grand Teton / footprints 986-988 of 6105")
	)
	(layers
		(0 "F.Cu" signal "TOP")
		(4 "In1.Cu" signal "GND")
		(6 "In2.Cu" signal "IN1")
		(8 "In3.Cu" signal "GND1")
		(10 "In4.Cu" signal "IN2")
		(12 "In5.Cu" signal "GND2")
		(14 "In6.Cu" signal "IN3")
		(16 "In7.Cu" signal "GND3")
		(18 "In8.Cu" signal "VCC")
		(20 "In9.Cu" signal "VCC1")
		(22 "In10.Cu" signal "GND4")
		(24 "In11.Cu" signal "IN4")
		(26 "In12.Cu" signal "GND5")
		(28 "In13.Cu" signal "IN5")
		(30 "In14.Cu" signal "GND6")
		(32 "In15.Cu" signal "IN6")
		(34 "In16.Cu" signal "GND7")
		(2 "B.Cu" signal "BOTTOM")
		(9 "F.Adhes" user "F.Adhesive")
		(11 "B.Adhes" user "B.Adhesive")
		(13 "F.Paste" user "Package Geometry/Pastemask Top")
		(15 "B.Paste" user "Package Geometry/Pastemask Bottom")
		(5 "F.SilkS" user "Ref Des/Silkscreen Top")
		(7 "B.SilkS" user "Ref Des/Silkscreen Bottom")
		(1 "F.Mask" user "Board Geometry/Soldermask Top")
		(3 "B.Mask" user "Board Geometry/Soldermask Bottom")
		(17 "Dwgs.User" user "User.Drawings")
		(19 "Cmts.User" user "User.Comments")
		(21 "Eco1.User" user "User.Eco1")
		(23 "Eco2.User" user "User.Eco2")
		(25 "Edge.Cuts" user "Board Geometry/Outline")
		(27 "Margin" user)
		(31 "F.CrtYd" user "Package Geometry/Place Bound Top")
		(29 "B.CrtYd" user "Package Geometry/Place Bound Bottom")
		(35 "F.Fab" user "Ref Des/Assembly Top")
		(33 "B.Fab" user "Ref Des/Assembly Bottom")
	)
	(footprint ""
		(layer "F.Cu")
		(at 362.49737 -355.340666 -90)
		(property "Reference" "PR345"
			(at 0 0 270)
			(layer "F.SilkS")
			(hide yes)
			(effects
				(font
					(size 1.27 1.27)
				)
			)
		)
		(property "Value" ""
			(at 0 0 270)
			(layer "F.Fab")
			(effects
				(font
					(size 1.27 1.27)
				)
			)
		)
		(duplicate_pad_numbers_are_jumpers no)
		(fp_line
			(start -0.7874 0.4064)
			(end -0.7874 -0.4064)
			(stroke
				(width 0.1524)
				(type default)
			)
			(layer "F.SilkS")
		)
		(fp_line
			(start 0.7874 0.4064)
			(end -0.7874 0.4064)
			(stroke
				(width 0.1524)
				(type default)
			)
			(layer "F.SilkS")
		)
		(fp_line
			(start -0.7874 -0.4064)
			(end 0.7874 -0.4064)
			(stroke
				(width 0.1524)
				(type default)
			)
			(layer "F.SilkS")
		)
		(fp_line
			(start 0.7874 -0.4064)
			(end 0.7874 0.4064)
			(stroke
				(width 0.1524)
				(type default)
			)
			(layer "F.SilkS")
		)
		(fp_line
			(start -0.67945 0.3048)
			(end -0.67945 -0.305054)
			(stroke
				(width 0.1)
				(type default)
			)
			(layer "F.Fab")
		)
		(fp_line
			(start -0.12065 0.3048)
			(end -0.67945 0.3048)
			(stroke
				(width 0.1)
				(type default)
			)
			(layer "F.Fab")
		)
		(fp_line
			(start 0.120396 0.3048)
			(end 0.120396 0.2794)
			(stroke
				(width 0.1)
				(type default)
			)
			(layer "F.Fab")
		)
		(fp_line
			(start 0.67945 0.3048)
			(end 0.120396 0.3048)
			(stroke
				(width 0.1)
				(type default)
			)
			(layer "F.Fab")
		)
		(fp_line
			(start -0.12065 0.2794)
			(end -0.12065 0.3048)
			(stroke
				(width 0.1)
				(type default)
			)
			(layer "F.Fab")
		)
		(fp_line
			(start 0.120396 0.2794)
			(end -0.12065 0.2794)
			(stroke
				(width 0.1)
				(type default)
			)
			(layer "F.Fab")
		)
		(fp_line
			(start -0.12065 -0.2794)
			(end 0.12065 -0.2794)
			(stroke
				(width 0.1)
				(type default)
			)
			(layer "F.Fab")
		)
		(fp_line
			(start 0.12065 -0.2794)
			(end 0.12065 -0.3048)
			(stroke
				(width 0.1)
				(type default)
			)
			(layer "F.Fab")
		)
		(fp_line
			(start 0.12065 -0.3048)
			(end 0.67945 -0.3048)
			(stroke
				(width 0.1)
				(type default)
			)
			(layer "F.Fab")
		)
		(fp_line
			(start 0.67945 -0.3048)
			(end 0.67945 0.3048)
			(stroke
				(width 0.1)
				(type default)
			)
			(layer "F.Fab")
		)
		(fp_line
			(start -0.67945 -0.305054)
			(end -0.12065 -0.305054)
			(stroke
				(width 0.1)
				(type default)
			)
			(layer "F.Fab")
		)
		(fp_line
			(start -0.12065 -0.305054)
			(end -0.12065 -0.2794)
			(stroke
				(width 0.1)
				(type default)
			)
			(layer "F.Fab")
		)
		(pad "1" smd circle
			(at -0.40005 0 270)
			(size 0 0)
			(layers "F.Cu" "F.Mask" "F.Paste")
			(net "SH_PVCCFA_EHV_FIVRA_CPU0")
		)
		(pad "2" smd circle
			(at 0.40005 0 270)
			(size 0 0)
			(layers "F.Cu" "F.Mask" "F.Paste")
			(net "SH_PVCCFA_EHV_FIVRA_CPU0_R")
		)
	)
	(footprint ""
		(layer "F.Cu")
		(at 255.45669 -39.482522 -90)
		(property "Reference" "PC2215"
			(at 0 0 270)
			(layer "F.SilkS")
			(hide yes)
			(effects
				(font
					(size 1.27 1.27)
				)
			)
		)
		(property "Value" ""
			(at 0 0 270)
			(layer "F.Fab")
			(effects
				(font
					(size 1.27 1.27)
				)
			)
		)
		(duplicate_pad_numbers_are_jumpers no)
		(fp_line
			(start -0.7874 0.4064)
			(end -0.7874 -0.4064)
			(stroke
				(width 0.1524)
				(type default)
			)
			(layer "F.SilkS")
		)
		(fp_line
			(start 0.7874 0.4064)
			(end -0.7874 0.4064)
			(stroke
				(width 0.1524)
				(type default)
			)
			(layer "F.SilkS")
		)
		(fp_line
			(start -0.7874 -0.4064)
			(end 0.7874 -0.4064)
			(stroke
				(width 0.1524)
				(type default)
			)
			(layer "F.SilkS")
		)
		(fp_line
			(start 0.7874 -0.4064)
			(end 0.7874 0.4064)
			(stroke
				(width 0.1524)
				(type default)
			)
			(layer "F.SilkS")
		)
		(fp_line
			(start -0.67945 0.3048)
			(end -0.67945 -0.305054)
			(stroke
				(width 0.1)
				(type default)
			)
			(layer "F.Fab")
		)
		(fp_line
			(start -0.12065 0.3048)
			(end -0.67945 0.3048)
			(stroke
				(width 0.1)
				(type default)
			)
			(layer "F.Fab")
		)
		(fp_line
			(start 0.120396 0.3048)
			(end 0.120396 0.2794)
			(stroke
				(width 0.1)
				(type default)
			)
			(layer "F.Fab")
		)
		(fp_line
			(start 0.67945 0.3048)
			(end 0.120396 0.3048)
			(stroke
				(width 0.1)
				(type default)
			)
			(layer "F.Fab")
		)
		(fp_line
			(start -0.12065 0.2794)
			(end -0.12065 0.3048)
			(stroke
				(width 0.1)
				(type default)
			)
			(layer "F.Fab")
		)
		(fp_line
			(start 0.120396 0.2794)
			(end -0.12065 0.2794)
			(stroke
				(width 0.1)
				(type default)
			)
			(layer "F.Fab")
		)
		(fp_line
			(start -0.12065 -0.2794)
			(end 0.12065 -0.2794)
			(stroke
				(width 0.1)
				(type default)
			)
			(layer "F.Fab")
		)
		(fp_line
			(start 0.12065 -0.2794)
			(end 0.12065 -0.3048)
			(stroke
				(width 0.1)
				(type default)
			)
			(layer "F.Fab")
		)
		(fp_line
			(start 0.12065 -0.3048)
			(end 0.67945 -0.3048)
			(stroke
				(width 0.1)
				(type default)
			)
			(layer "F.Fab")
		)
		(fp_line
			(start 0.67945 -0.3048)
			(end 0.67945 0.3048)
			(stroke
				(width 0.1)
				(type default)
			)
			(layer "F.Fab")
		)
		(fp_line
			(start -0.67945 -0.305054)
			(end -0.12065 -0.305054)
			(stroke
				(width 0.1)
				(type default)
			)
			(layer "F.Fab")
		)
		(fp_line
			(start -0.12065 -0.305054)
			(end -0.12065 -0.2794)
			(stroke
				(width 0.1)
				(type default)
			)
			(layer "F.Fab")
		)
		(pad "1" smd circle
			(at -0.40005 0 270)
			(size 0 0)
			(layers "F.Cu" "F.Mask" "F.Paste")
			(net "P12V_E1S_GATE_0")
		)
		(pad "2" smd circle
			(at 0.40005 0 270)
			(size 0 0)
			(layers "F.Cu" "F.Mask" "F.Paste")
			(net "GND")
		)
	)
	(footprint ""
		(layer "F.Cu")
		(at 186.8678 -358.14635)
		(property "Reference" "PC726_P1_3"
			(at 0 0 0)
			(layer "F.SilkS")
			(hide yes)
			(effects
				(font
					(size 1.27 1.27)
				)
			)
		)
		(property "Value" ""
			(at 0 0 0)
			(layer "F.Fab")
			(effects
				(font
					(size 1.27 1.27)
				)
			)
		)
		(duplicate_pad_numbers_are_jumpers no)
		(fp_line
			(start -1.524 -0.762)
			(end 1.524 -0.762)
			(stroke
				(width 0.1524)
				(type default)
			)
			(layer "F.SilkS")
		)
		(fp_line
			(start -1.524 0.762)
			(end -1.524 -0.762)
			(stroke
				(width 0.1524)
				(type default)
			)
			(layer "F.SilkS")
		)
		(fp_line
			(start 1.524 -0.762)
			(end 1.524 0.762)
			(stroke
				(width 0.1524)
				(type default)
			)
			(layer "F.SilkS")
		)
		(fp_line
			(start 1.524 0.762)
			(end -1.524 0.762)
			(stroke
				(width 0.1524)
				(type default)
			)
			(layer "F.SilkS")
		)
		(fp_line
			(start -1.1049 -0.724916)
			(end -1.1049 0.724916)
			(stroke
				(width 0.1)
				(type default)
			)
			(layer "F.Fab")
		)
		(fp_line
			(start -1.1049 0.724916)
			(end 1.1049 0.724916)
			(stroke
				(width 0.1)
				(type default)
			)
			(layer "F.Fab")
		)
		(fp_line
			(start 1.1049 -0.724916)
			(end -1.1049 -0.724916)
			(stroke
				(width 0.1)
				(type default)
			)
			(layer "F.Fab")
		)
		(fp_line
			(start 1.1049 0.724916)
			(end 1.1049 -0.724916)
			(stroke
				(width 0.1)
				(type default)
			)
			(layer "F.Fab")
		)
		(pad "1" smd rect
			(at -0.889 0 180)
			(size 1.016 1.27)
			(layers "F.Cu" "F.Mask" "F.Paste")
			(net "SW_P12V_PVCCFA_EHV_FIVRA_CPU1_R")
		)
		(pad "2" smd rect
			(at 0.889 0 180)
			(size 1.016 1.27)
			(layers "F.Cu" "F.Mask" "F.Paste")
			(net "GND")
		)
	)
)
